(kicad_pcb
	(version 20260206)
	(generator "pcbnew")
	(generator_version "10.0")
	(general
		(thickness 1.6)
		(legacy_teardrops no)
	)
	(paper "A4")
	(title_block
		(title "03242023_DA0F0TMBIJ0_F0T_Motherboard_J_brd_V01_OCP.brd")
		(comment 1 "Grand Teton / footprints 4440-4445 of 6105")
	)
	(layers
		(0 "F.Cu" signal "TOP")
		(4 "In1.Cu" signal "GND")
		(6 "In2.Cu" signal "IN1")
		(8 "In3.Cu" signal "GND1")
		(10 "In4.Cu" signal "IN2")
		(12 "In5.Cu" signal "GND2")
		(14 "In6.Cu" signal "IN3")
		(16 "In7.Cu" signal "GND3")
		(18 "In8.Cu" signal "VCC")
		(20 "In9.Cu" signal "VCC1")
		(22 "In10.Cu" signal "GND4")
		(24 "In11.Cu" signal "IN4")
		(26 "In12.Cu" signal "GND5")
		(28 "In13.Cu" signal "IN5")
		(30 "In14.Cu" signal "GND6")
		(32 "In15.Cu" signal "IN6")
		(34 "In16.Cu" signal "GND7")
		(2 "B.Cu" signal "BOTTOM")
		(9 "F.Adhes" user "F.Adhesive")
		(11 "B.Adhes" user "B.Adhesive")
		(13 "F.Paste" user "Package Geometry/Pastemask Top")
		(15 "B.Paste" user "Package Geometry/Pastemask Bottom")
		(5 "F.SilkS" user "Ref Des/Silkscreen Top")
		(7 "B.SilkS" user "Ref Des/Silkscreen Bottom")
		(1 "F.Mask" user "Board Geometry/Soldermask Top")
		(3 "B.Mask" user "Board Geometry/Soldermask Bottom")
		(17 "Dwgs.User" user "User.Drawings")
		(19 "Cmts.User" user "User.Comments")
		(21 "Eco1.User" user "User.Eco1")
		(23 "Eco2.User" user "User.Eco2")
		(25 "Edge.Cuts" user "Board Geometry/Outline")
		(27 "Margin" user)
		(31 "F.CrtYd" user "Package Geometry/Place Bound Top")
		(29 "B.CrtYd" user "Package Geometry/Place Bound Bottom")
		(35 "F.Fab" user "Ref Des/Assembly Top")
		(33 "B.Fab" user "Ref Des/Assembly Bottom")
	)
	(footprint ""
		(layer "B.Cu")
		(at 206.162656 -70.31228 180)
		(property "Reference" "R3214"
			(at 0 0 0)
			(layer "B.SilkS")
			(hide yes)
			(effects
				(font
					(size 1.27 1.27)
				)
				(justify mirror)
			)
		)
		(property "Value" ""
			(at 0 0 0)
			(layer "B.Fab")
			(effects
				(font
					(size 1.27 1.27)
				)
				(justify mirror)
			)
		)
		(duplicate_pad_numbers_are_jumpers no)
		(fp_line
			(start 0.7874 0.4064)
			(end 0.7874 -0.4064)
			(stroke
				(width 0.1524)
				(type default)
			)
			(layer "B.SilkS")
		)
		(fp_line
			(start 0.7874 -0.4064)
			(end -0.7874 -0.4064)
			(stroke
				(width 0.1524)
				(type default)
			)
			(layer "B.SilkS")
		)
		(fp_line
			(start -0.7874 0.4064)
			(end 0.7874 0.4064)
			(stroke
				(width 0.1524)
				(type default)
			)
			(layer "B.SilkS")
		)
		(fp_line
			(start -0.7874 -0.4064)
			(end -0.7874 0.4064)
			(stroke
				(width 0.1524)
				(type default)
			)
			(layer "B.SilkS")
		)
		(fp_line
			(start 0.67945 0.3048)
			(end 0.67945 -0.305054)
			(stroke
				(width 0.1)
				(type default)
			)
			(layer "B.Fab")
		)
		(fp_line
			(start 0.67945 -0.305054)
			(end 0.12065 -0.305054)
			(stroke
				(width 0.1)
				(type default)
			)
			(layer "B.Fab")
		)
		(fp_line
			(start 0.12065 0.3048)
			(end 0.67945 0.3048)
			(stroke
				(width 0.1)
				(type default)
			)
			(layer "B.Fab")
		)
		(fp_line
			(start 0.12065 0.2794)
			(end 0.12065 0.3048)
			(stroke
				(width 0.1)
				(type default)
			)
			(layer "B.Fab")
		)
		(fp_line
			(start 0.12065 -0.2794)
			(end -0.12065 -0.2794)
			(stroke
				(width 0.1)
				(type default)
			)
			(layer "B.Fab")
		)
		(fp_line
			(start 0.12065 -0.305054)
			(end 0.12065 -0.2794)
			(stroke
				(width 0.1)
				(type default)
			)
			(layer "B.Fab")
		)
		(fp_line
			(start -0.120396 0.3048)
			(end -0.120396 0.2794)
			(stroke
				(width 0.1)
				(type default)
			)
			(layer "B.Fab")
		)
		(fp_line
			(start -0.120396 0.2794)
			(end 0.12065 0.2794)
			(stroke
				(width 0.1)
				(type default)
			)
			(layer "B.Fab")
		)
		(fp_line
			(start -0.12065 -0.2794)
			(end -0.12065 -0.3048)
			(stroke
				(width 0.1)
				(type default)
			)
			(layer "B.Fab")
		)
		(fp_line
			(start -0.12065 -0.3048)
			(end -0.67945 -0.3048)
			(stroke
				(width 0.1)
				(type default)
			)
			(layer "B.Fab")
		)
		(fp_line
			(start -0.67945 0.3048)
			(end -0.120396 0.3048)
			(stroke
				(width 0.1)
				(type default)
			)
			(layer "B.Fab")
		)
		(fp_line
			(start -0.67945 -0.3048)
			(end -0.67945 0.3048)
			(stroke
				(width 0.1)
				(type default)
			)
			(layer "B.Fab")
		)
		(pad "1" smd circle
			(at 0.40005 0)
			(size 0 0)
			(layers "B.Cu" "B.Mask" "B.Paste")
			(net "NCSI_BMC_TXD0_R1")
		)
		(pad "2" smd circle
			(at -0.40005 0)
			(size 0 0)
			(layers "B.Cu" "B.Mask" "B.Paste")
			(net "RMII_BMC_OCP_TXD_0")
		)
	)
	(footprint ""
		(layer "B.Cu")
		(at 402.336 -190.845948 -90)
		(property "Reference" "R4298"
			(at 0 0 90)
			(layer "B.SilkS")
			(hide yes)
			(effects
				(font
					(size 1.27 1.27)
				)
				(justify mirror)
			)
		)
		(property "Value" ""
			(at 0 0 90)
			(layer "B.Fab")
			(effects
				(font
					(size 1.27 1.27)
				)
				(justify mirror)
			)
		)
		(duplicate_pad_numbers_are_jumpers no)
		(fp_line
			(start -0.7874 0.4064)
			(end 0.7874 0.4064)
			(stroke
				(width 0.1524)
				(type default)
			)
			(layer "B.SilkS")
		)
		(fp_line
			(start 0.7874 0.4064)
			(end 0.7874 -0.4064)
			(stroke
				(width 0.1524)
				(type default)
			)
			(layer "B.SilkS")
		)
		(fp_line
			(start -0.7874 -0.4064)
			(end -0.7874 0.4064)
			(stroke
				(width 0.1524)
				(type default)
			)
			(layer "B.SilkS")
		)
		(fp_line
			(start 0.7874 -0.4064)
			(end -0.7874 -0.4064)
			(stroke
				(width 0.1524)
				(type default)
			)
			(layer "B.SilkS")
		)
		(fp_line
			(start -0.67945 0.3048)
			(end -0.120396 0.3048)
			(stroke
				(width 0.1)
				(type default)
			)
			(layer "B.Fab")
		)
		(fp_line
			(start -0.120396 0.3048)
			(end -0.120396 0.2794)
			(stroke
				(width 0.1)
				(type default)
			)
			(layer "B.Fab")
		)
		(fp_line
			(start 0.12065 0.3048)
			(end 0.67945 0.3048)
			(stroke
				(width 0.1)
				(type default)
			)
			(layer "B.Fab")
		)
		(fp_line
			(start 0.67945 0.3048)
			(end 0.67945 -0.305054)
			(stroke
				(width 0.1)
				(type default)
			)
			(layer "B.Fab")
		)
		(fp_line
			(start -0.120396 0.2794)
			(end 0.12065 0.2794)
			(stroke
				(width 0.1)
				(type default)
			)
			(layer "B.Fab")
		)
		(fp_line
			(start 0.12065 0.2794)
			(end 0.12065 0.3048)
			(stroke
				(width 0.1)
				(type default)
			)
			(layer "B.Fab")
		)
		(fp_line
			(start -0.12065 -0.2794)
			(end -0.12065 -0.3048)
			(stroke
				(width 0.1)
				(type default)
			)
			(layer "B.Fab")
		)
		(fp_line
			(start 0.12065 -0.2794)
			(end -0.12065 -0.2794)
			(stroke
				(width 0.1)
				(type default)
			)
			(layer "B.Fab")
		)
		(fp_line
			(start -0.67945 -0.3048)
			(end -0.67945 0.3048)
			(stroke
				(width 0.1)
				(type default)
			)
			(layer "B.Fab")
		)
		(fp_line
			(start -0.12065 -0.3048)
			(end -0.67945 -0.3048)
			(stroke
				(width 0.1)
				(type default)
			)
			(layer "B.Fab")
		)
		(fp_line
			(start 0.12065 -0.305054)
			(end 0.12065 -0.2794)
			(stroke
				(width 0.1)
				(type default)
			)
			(layer "B.Fab")
		)
		(fp_line
			(start 0.67945 -0.305054)
			(end 0.12065 -0.305054)
			(stroke
				(width 0.1)
				(type default)
			)
			(layer "B.Fab")
		)
		(pad "1" smd circle
			(at 0.40005 0 90)
			(size 0 0)
			(layers "B.Cu" "B.Mask" "B.Paste")
			(net "PWRGD_DRAMPWRGD_CPU0_GH_LVC1_R2")
		)
		(pad "2" smd circle
			(at -0.40005 0 90)
			(size 0 0)
			(layers "B.Cu" "B.Mask" "B.Paste")
			(net "PWRGD_DRAMPWRGD_CPU0_GH_LVC1_R")
		)
	)
	(footprint ""
		(layer "B.Cu")
		(at 338.441792 -137.832338)
		(property "Reference" "R1013"
			(at 0 0 0)
			(layer "B.SilkS")
			(hide yes)
			(effects
				(font
					(size 1.27 1.27)
				)
				(justify mirror)
			)
		)
		(property "Value" ""
			(at 0 0 0)
			(layer "B.Fab")
			(effects
				(font
					(size 1.27 1.27)
				)
				(justify mirror)
			)
		)
		(duplicate_pad_numbers_are_jumpers no)
		(fp_line
			(start -0.7874 -0.4064)
			(end -0.7874 0.4064)
			(stroke
				(width 0.1524)
				(type default)
			)
			(layer "B.SilkS")
		)
		(fp_line
			(start -0.7874 0.4064)
			(end -0.281432 0.4064)
			(stroke
				(width 0.1524)
				(type default)
			)
			(layer "B.SilkS")
		)
		(fp_line
			(start 0.333248 0.4064)
			(end 0.7874 0.4064)
			(stroke
				(width 0.1524)
				(type default)
			)
			(layer "B.SilkS")
		)
		(fp_line
			(start 0.7874 -0.4064)
			(end -0.7874 -0.4064)
			(stroke
				(width 0.1524)
				(type default)
			)
			(layer "B.SilkS")
		)
		(fp_line
			(start 0.7874 -0.18161)
			(end 0.7874 -0.4064)
			(stroke
				(width 0.1524)
				(type default)
			)
			(layer "B.SilkS")
		)
		(fp_line
			(start 0.7874 0.4064)
			(end 0.7874 0.21971)
			(stroke
				(width 0.1524)
				(type default)
			)
			(layer "B.SilkS")
		)
		(fp_line
			(start -0.67945 -0.3048)
			(end -0.67945 0.3048)
			(stroke
				(width 0.1)
				(type default)
			)
			(layer "B.Fab")
		)
		(fp_line
			(start -0.67945 0.3048)
			(end -0.120396 0.3048)
			(stroke
				(width 0.1)
				(type default)
			)
			(layer "B.Fab")
		)
		(fp_line
			(start -0.12065 -0.3048)
			(end -0.67945 -0.3048)
			(stroke
				(width 0.1)
				(type default)
			)
			(layer "B.Fab")
		)
		(fp_line
			(start -0.12065 -0.2794)
			(end -0.12065 -0.3048)
			(stroke
				(width 0.1)
				(type default)
			)
			(layer "B.Fab")
		)
		(fp_line
			(start -0.120396 0.2794)
			(end 0.12065 0.2794)
			(stroke
				(width 0.1)
				(type default)
			)
			(layer "B.Fab")
		)
		(fp_line
			(start -0.120396 0.3048)
			(end -0.120396 0.2794)
			(stroke
				(width 0.1)
				(type default)
			)
			(layer "B.Fab")
		)
		(fp_line
			(start 0.12065 -0.305054)
			(end 0.12065 -0.2794)
			(stroke
				(width 0.1)
				(type default)
			)
			(layer "B.Fab")
		)
		(fp_line
			(start 0.12065 -0.2794)
			(end -0.12065 -0.2794)
			(stroke
				(width 0.1)
				(type default)
			)
			(layer "B.Fab")
		)
		(fp_line
			(start 0.12065 0.2794)
			(end 0.12065 0.3048)
			(stroke
				(width 0.1)
				(type default)
			)
			(layer "B.Fab")
		)
		(fp_line
			(start 0.12065 0.3048)
			(end 0.67945 0.3048)
			(stroke
				(width 0.1)
				(type default)
			)
			(layer "B.Fab")
		)
		(fp_line
			(start 0.67945 -0.305054)
			(end 0.12065 -0.305054)
			(stroke
				(width 0.1)
				(type default)
			)
			(layer "B.Fab")
		)
		(fp_line
			(start 0.67945 0.3048)
			(end 0.67945 -0.305054)
			(stroke
				(width 0.1)
				(type default)
			)
			(layer "B.Fab")
		)
		(pad "1" smd rect
			(at 0.40005 0)
			(size 0.4572 0.508)
			(layers "B.Cu" "B.Mask" "B.Paste")
			(net "CLK_25M_PCH_CPU0_DP")
		)
		(pad "2" smd rect
			(at -0.40005 0)
			(size 0.4572 0.508)
			(layers "B.Cu" "B.Mask" "B.Paste")
			(net "CLK_25M_NSSC_CPU0_DP")
		)
	)
	(footprint ""
		(layer "B.Cu")
		(at 102.909624 -334.845152 -90)
		(property "Reference" "PR327"
			(at 0 0 90)
			(layer "B.SilkS")
			(hide yes)
			(effects
				(font
					(size 1.27 1.27)
				)
				(justify mirror)
			)
		)
		(property "Value" ""
			(at 0 0 90)
			(layer "B.Fab")
			(effects
				(font
					(size 1.27 1.27)
				)
				(justify mirror)
			)
		)
		(duplicate_pad_numbers_are_jumpers no)
		(fp_line
			(start -0.7874 0.4064)
			(end 0.7874 0.4064)
			(stroke
				(width 0.1524)
				(type default)
			)
			(layer "B.SilkS")
		)
		(fp_line
			(start 0.7874 0.4064)
			(end 0.7874 -0.4064)
			(stroke
				(width 0.1524)
				(type default)
			)
			(layer "B.SilkS")
		)
		(fp_line
			(start -0.7874 -0.4064)
			(end -0.7874 0.4064)
			(stroke
				(width 0.1524)
				(type default)
			)
			(layer "B.SilkS")
		)
		(fp_line
			(start 0.7874 -0.4064)
			(end -0.7874 -0.4064)
			(stroke
				(width 0.1524)
				(type default)
			)
			(layer "B.SilkS")
		)
		(fp_line
			(start -0.67945 0.3048)
			(end -0.120396 0.3048)
			(stroke
				(width 0.1)
				(type default)
			)
			(layer "B.Fab")
		)
		(fp_line
			(start -0.120396 0.3048)
			(end -0.120396 0.2794)
			(stroke
				(width 0.1)
				(type default)
			)
			(layer "B.Fab")
		)
		(fp_line
			(start 0.12065 0.3048)
			(end 0.67945 0.3048)
			(stroke
				(width 0.1)
				(type default)
			)
			(layer "B.Fab")
		)
		(fp_line
			(start 0.67945 0.3048)
			(end 0.67945 -0.305054)
			(stroke
				(width 0.1)
				(type default)
			)
			(layer "B.Fab")
		)
		(fp_line
			(start -0.120396 0.2794)
			(end 0.12065 0.2794)
			(stroke
				(width 0.1)
				(type default)
			)
			(layer "B.Fab")
		)
		(fp_line
			(start 0.12065 0.2794)
			(end 0.12065 0.3048)
			(stroke
				(width 0.1)
				(type default)
			)
			(layer "B.Fab")
		)
		(fp_line
			(start -0.12065 -0.2794)
			(end -0.12065 -0.3048)
			(stroke
				(width 0.1)
				(type default)
			)
			(layer "B.Fab")
		)
		(fp_line
			(start 0.12065 -0.2794)
			(end -0.12065 -0.2794)
			(stroke
				(width 0.1)
				(type default)
			)
			(layer "B.Fab")
		)
		(fp_line
			(start -0.67945 -0.3048)
			(end -0.67945 0.3048)
			(stroke
				(width 0.1)
				(type default)
			)
			(layer "B.Fab")
		)
		(fp_line
			(start -0.12065 -0.3048)
			(end -0.67945 -0.3048)
			(stroke
				(width 0.1)
				(type default)
			)
			(layer "B.Fab")
		)
		(fp_line
			(start 0.12065 -0.305054)
			(end 0.12065 -0.2794)
			(stroke
				(width 0.1)
				(type default)
			)
			(layer "B.Fab")
		)
		(fp_line
			(start 0.67945 -0.305054)
			(end 0.12065 -0.305054)
			(stroke
				(width 0.1)
				(type default)
			)
			(layer "B.Fab")
		)
		(pad "1" smd circle
			(at 0.40005 0 90)
			(size 0 0)
			(layers "B.Cu" "B.Mask" "B.Paste")
			(net "PVCCIN_CPU1_PVCC")
		)
		(pad "2" smd circle
			(at -0.40005 0 90)
			(size 0 0)
			(layers "B.Cu" "B.Mask" "B.Paste")
			(net "PVCCIN_CPU1_VDD2")
		)
	)
	(footprint ""
		(layer "B.Cu")
		(at 16.237712 -112.693958 180)
		(property "Reference" "C5236"
			(at 0 0 0)
			(layer "B.SilkS")
			(hide yes)
			(effects
				(font
					(size 1.27 1.27)
				)
				(justify mirror)
			)
		)
		(property "Value" ""
			(at 0 0 0)
			(layer "B.Fab")
			(effects
				(font
					(size 1.27 1.27)
				)
				(justify mirror)
			)
		)
		(duplicate_pad_numbers_are_jumpers no)
		(fp_line
			(start 0.7874 0.4064)
			(end 0.7874 -0.4064)
			(stroke
				(width 0.1524)
				(type default)
			)
			(layer "B.SilkS")
		)
		(fp_line
			(start 0.7874 -0.4064)
			(end -0.7874 -0.4064)
			(stroke
				(width 0.1524)
				(type default)
			)
			(layer "B.SilkS")
		)
		(fp_line
			(start -0.7874 0.4064)
			(end 0.7874 0.4064)
			(stroke
				(width 0.1524)
				(type default)
			)
			(layer "B.SilkS")
		)
		(fp_line
			(start -0.7874 -0.4064)
			(end -0.7874 0.4064)
			(stroke
				(width 0.1524)
				(type default)
			)
			(layer "B.SilkS")
		)
		(fp_line
			(start 0.67945 0.3048)
			(end 0.67945 -0.305054)
			(stroke
				(width 0.1)
				(type default)
			)
			(layer "B.Fab")
		)
		(fp_line
			(start 0.67945 -0.305054)
			(end 0.12065 -0.305054)
			(stroke
				(width 0.1)
				(type default)
			)
			(layer "B.Fab")
		)
		(fp_line
			(start 0.12065 0.3048)
			(end 0.67945 0.3048)
			(stroke
				(width 0.1)
				(type default)
			)
			(layer "B.Fab")
		)
		(fp_line
			(start 0.12065 0.2794)
			(end 0.12065 0.3048)
			(stroke
				(width 0.1)
				(type default)
			)
			(layer "B.Fab")
		)
		(fp_line
			(start 0.12065 -0.2794)
			(end -0.12065 -0.2794)
			(stroke
				(width 0.1)
				(type default)
			)
			(layer "B.Fab")
		)
		(fp_line
			(start 0.12065 -0.305054)
			(end 0.12065 -0.2794)
			(stroke
				(width 0.1)
				(type default)
			)
			(layer "B.Fab")
		)
		(fp_line
			(start -0.120396 0.3048)
			(end -0.120396 0.2794)
			(stroke
				(width 0.1)
				(type default)
			)
			(layer "B.Fab")
		)
		(fp_line
			(start -0.120396 0.2794)
			(end 0.12065 0.2794)
			(stroke
				(width 0.1)
				(type default)
			)
			(layer "B.Fab")
		)
		(fp_line
			(start -0.12065 -0.2794)
			(end -0.12065 -0.3048)
			(stroke
				(width 0.1)
				(type default)
			)
			(layer "B.Fab")
		)
		(fp_line
			(start -0.12065 -0.3048)
			(end -0.67945 -0.3048)
			(stroke
				(width 0.1)
				(type default)
			)
			(layer "B.Fab")
		)
		(fp_line
			(start -0.67945 0.3048)
			(end -0.120396 0.3048)
			(stroke
				(width 0.1)
				(type default)
			)
			(layer "B.Fab")
		)
		(fp_line
			(start -0.67945 -0.3048)
			(end -0.67945 0.3048)
			(stroke
				(width 0.1)
				(type default)
			)
			(layer "B.Fab")
		)
		(pad "1" smd circle
			(at 0.40005 0)
			(size 0 0)
			(layers "B.Cu" "B.Mask" "B.Paste")
			(net "PD_U5201_VREG")
		)
		(pad "2" smd circle
			(at -0.40005 0)
			(size 0 0)
			(layers "B.Cu" "B.Mask" "B.Paste")
			(net "GND")
		)
	)
	(footprint ""
		(layer "B.Cu")
		(at 299.609002 -317.243714 90)
		(property "Reference" "R3875"
			(at 0 0 90)
			(layer "B.SilkS")
			(hide yes)
			(effects
				(font
					(size 1.27 1.27)
				)
				(justify mirror)
			)
		)
		(property "Value" ""
			(at 0 0 90)
			(layer "B.Fab")
			(effects
				(font
					(size 1.27 1.27)
				)
				(justify mirror)
			)
		)
		(duplicate_pad_numbers_are_jumpers no)
		(fp_line
			(start 0.7874 -0.4064)
			(end -0.7874 -0.4064)
			(stroke
				(width 0.1524)
				(type default)
			)
			(layer "B.SilkS")
		)
		(fp_line
			(start -0.7874 -0.4064)
			(end -0.7874 0.4064)
			(stroke
				(width 0.1524)
				(type default)
			)
			(layer "B.SilkS")
		)
		(fp_line
			(start 0.7874 0.4064)
			(end 0.7874 -0.4064)
			(stroke
				(width 0.1524)
				(type default)
			)
			(layer "B.SilkS")
		)
		(fp_line
			(start -0.7874 0.4064)
			(end 0.7874 0.4064)
			(stroke
				(width 0.1524)
				(type default)
			)
			(layer "B.SilkS")
		)
		(fp_line
			(start 0.67945 -0.305054)
			(end 0.12065 -0.305054)
			(stroke
				(width 0.1)
				(type default)
			)
			(layer "B.Fab")
		)
		(fp_line
			(start 0.12065 -0.305054)
			(end 0.12065 -0.2794)
			(stroke
				(width 0.1)
				(type default)
			)
			(layer "B.Fab")
		)
		(fp_line
			(start -0.12065 -0.3048)
			(end -0.67945 -0.3048)
			(stroke
				(width 0.1)
				(type default)
			)
			(layer "B.Fab")
		)
		(fp_line
			(start -0.67945 -0.3048)
			(end -0.67945 0.3048)
			(stroke
				(width 0.1)
				(type default)
			)
			(layer "B.Fab")
		)
		(fp_line
			(start 0.12065 -0.2794)
			(end -0.12065 -0.2794)
			(stroke
				(width 0.1)
				(type default)
			)
			(layer "B.Fab")
		)
		(fp_line
			(start -0.12065 -0.2794)
			(end -0.12065 -0.3048)
			(stroke
				(width 0.1)
				(type default)
			)
			(layer "B.Fab")
		)
		(fp_line
			(start 0.12065 0.2794)
			(end 0.12065 0.3048)
			(stroke
				(width 0.1)
				(type default)
			)
			(layer "B.Fab")
		)
		(fp_line
			(start -0.120396 0.2794)
			(end 0.12065 0.2794)
			(stroke
				(width 0.1)
				(type default)
			)
			(layer "B.Fab")
		)
		(fp_line
			(start 0.67945 0.3048)
			(end 0.67945 -0.305054)
			(stroke
				(width 0.1)
				(type default)
			)
			(layer "B.Fab")
		)
		(fp_line
			(start 0.12065 0.3048)
			(end 0.67945 0.3048)
			(stroke
				(width 0.1)
				(type default)
			)
			(layer "B.Fab")
		)
		(fp_line
			(start -0.120396 0.3048)
			(end -0.120396 0.2794)
			(stroke
				(width 0.1)
				(type default)
			)
			(layer "B.Fab")
		)
		(fp_line
			(start -0.67945 0.3048)
			(end -0.120396 0.3048)
			(stroke
				(width 0.1)
				(type default)
			)
			(layer "B.Fab")
		)
		(pad "1" smd circle
			(at 0.40005 0 270)
			(size 0 0)
			(layers "B.Cu" "B.Mask" "B.Paste")
			(net "I3C_SPD_DDRABCD_CPU0_LVC1_SCL_R")
		)
		(pad "2" smd circle
			(at -0.40005 0 270)
			(size 0 0)
			(layers "B.Cu" "B.Mask" "B.Paste")
			(net "I3C_SPD_DDRABCD_CPU0_LVC1_SCL")
		)
	)
)
